(kicad_pcb
	(version 20260206)
	(generator "pcbnew")
	(generator_version "10.0")
	(general
		(thickness 1.6)
		(legacy_teardrops no)
	)
	(paper "A4")
	(title_block
		(title "Wiwynn_Tioga_Pass_MB.brd")
		(comment 1 "Tioga Pass / footprints 2748-2754 of 4770")
	)
	(layers
		(0 "F.Cu" signal "TOP")
		(4 "In1.Cu" signal "L2GND")
		(6 "In2.Cu" signal "L3")
		(8 "In3.Cu" signal "L4GND")
		(10 "In4.Cu" signal "L5")
		(12 "In5.Cu" signal "L6GND")
		(14 "In6.Cu" signal "L7VCC")
		(16 "In7.Cu" signal "L8VCC")
		(18 "In8.Cu" signal "L9GND")
		(20 "In9.Cu" signal "L10")
		(22 "In10.Cu" signal "L11GND")
		(24 "In11.Cu" signal "L12")
		(26 "In12.Cu" signal "L13GND")
		(2 "B.Cu" signal "BOTTOM")
		(9 "F.Adhes" user "F.Adhesive")
		(11 "B.Adhes" user "B.Adhesive")
		(13 "F.Paste" user "Package Geometry/Pastemask Top")
		(15 "B.Paste" user "Package Geometry/Pastemask Bottom")
		(5 "F.SilkS" user "Ref Des/Silkscreen Top")
		(7 "B.SilkS" user "Ref Des/Silkscreen Bottom")
		(1 "F.Mask" user "Board Geometry/Soldermask Top")
		(3 "B.Mask" user "Board Geometry/Soldermask Bottom")
		(17 "Dwgs.User" user "User.Drawings")
		(19 "Cmts.User" user "User.Comments")
		(21 "Eco1.User" user "User.Eco1")
		(23 "Eco2.User" user "User.Eco2")
		(25 "Edge.Cuts" user "Board Geometry/Outline")
		(27 "Margin" user)
		(31 "F.CrtYd" user "Package Geometry/Place Bound Top")
		(29 "B.CrtYd" user "Package Geometry/Place Bound Bottom")
		(35 "F.Fab" user "Ref Des/Assembly Top")
		(33 "B.Fab" user "Ref Des/Assembly Bottom")
	)
	(footprint ""
		(layer "B.Cu")
		(at 420.503604 -75.048872 180)
		(property "Reference" "U1R1"
			(at -1.24333 2.032 270)
			(unlocked yes)
			(layer "B.SilkS")
			(effects
				(font
					(size 0.7874 0.5842)
					(thickness 0.1524)
				)
				(justify left mirror)
			)
		)
		(property "Value" ""
			(at 0 0 0)
			(layer "B.Fab")
			(effects
				(font
					(size 1.27 1.27)
				)
				(justify mirror)
			)
		)
		(duplicate_pad_numbers_are_jumpers no)
		(fp_circle
			(center 0.351536 -0.648462)
			(end 0.224536 -0.648462)
			(stroke
				(width 0.254)
				(type default)
			)
			(fill no)
			(layer "B.SilkS")
		)
		(fp_poly
			(pts
				(xy -0.21463 -0.450088) (xy -1.56337 -0.450088) (xy -1.56337 1.75006) (xy -0.21463 1.75006)
			)
			(stroke
				(width 0)
				(type default)
			)
			(fill no)
			(layer "B.CrtYd")
		)
		(fp_line
			(start -0.21463 1.75006)
			(end -0.21463 -0.450088)
			(stroke
				(width 0.1)
				(type default)
			)
			(layer "B.Fab")
		)
		(fp_line
			(start -0.21463 -0.450088)
			(end -1.56337 -0.450088)
			(stroke
				(width 0.1)
				(type default)
			)
			(layer "B.Fab")
		)
		(fp_line
			(start -1.56337 1.75006)
			(end -0.21463 1.75006)
			(stroke
				(width 0.1)
				(type default)
			)
			(layer "B.Fab")
		)
		(fp_line
			(start -1.56337 -0.450088)
			(end -1.56337 1.75006)
			(stroke
				(width 0.1)
				(type default)
			)
			(layer "B.Fab")
		)
		(fp_circle
			(center 0.4699 -0.8382)
			(end 0.3429 -0.8382)
			(stroke
				(width 0.254)
				(type default)
			)
			(fill no)
			(layer "B.Fab")
		)
		(pad "1" smd rect
			(at 0 0)
			(size 1.016 0.381)
			(layers "B.Cu" "B.Mask" "B.Paste")
			(net "Net_6472")
		)
		(pad "2" smd rect
			(at 0 0.649986)
			(size 1.016 0.381)
			(layers "B.Cu" "B.Mask" "B.Paste")
			(net "FM_FAST_PROCHOT_THROTTLE_DLY_BU")
		)
		(pad "3" smd rect
			(at 0 1.299972)
			(size 1.016 0.381)
			(layers "B.Cu" "B.Mask" "B.Paste")
			(net "GND")
		)
		(pad "4" smd rect
			(at -1.778 1.299972)
			(size 1.016 0.381)
			(layers "B.Cu" "B.Mask" "B.Paste")
			(net "FM_THROTTLE_R1_N")
		)
		(pad "5" smd rect
			(at -1.778 0)
			(size 1.016 0.381)
			(layers "B.Cu" "B.Mask" "B.Paste")
			(net "P3V3_STBY")
		)
	)
	(footprint ""
		(layer "B.Cu")
		(at 80.391 -64.262 -90)
		(property "Reference" "R8R1"
			(at 0 0 90)
			(layer "B.SilkS")
			(hide yes)
			(effects
				(font
					(size 1.27 1.27)
				)
				(justify mirror)
			)
		)
		(property "Value" ""
			(at 0 0 90)
			(layer "B.Fab")
			(effects
				(font
					(size 1.27 1.27)
				)
				(justify mirror)
			)
		)
		(duplicate_pad_numbers_are_jumpers no)
		(fp_poly
			(pts
				(xy 0.2794 -0.1016) (xy -0.2794 -0.1016) (xy -0.2794 0.9906) (xy 0.2794 0.9906)
			)
			(stroke
				(width 0)
				(type default)
			)
			(fill no)
			(layer "B.CrtYd")
		)
		(fp_line
			(start -0.2794 0.9906)
			(end -0.2794 -0.1016)
			(stroke
				(width 0.1)
				(type default)
			)
			(layer "B.Fab")
		)
		(fp_line
			(start 0.2794 0.9906)
			(end -0.2794 0.9906)
			(stroke
				(width 0.1)
				(type default)
			)
			(layer "B.Fab")
		)
		(fp_line
			(start -0.2794 -0.1016)
			(end 0.2794 -0.1016)
			(stroke
				(width 0.1)
				(type default)
			)
			(layer "B.Fab")
		)
		(fp_line
			(start 0.2794 -0.1016)
			(end 0.2794 0.9906)
			(stroke
				(width 0.1)
				(type default)
			)
			(layer "B.Fab")
		)
		(pad "1" smd rect
			(at 0 0 90)
			(size 0.508 0.508)
			(layers "B.Cu" "B.Mask" "B.Paste")
			(net "PD_CPU1_RSVD_TEST_1")
		)
		(pad "2" smd rect
			(at 0 0.889 90)
			(size 0.508 0.508)
			(layers "B.Cu" "B.Mask" "B.Paste")
			(net "GND")
		)
		(zone
			(layer "B.Cu")
			(hatch none 0.5)
			(connect_pads
				(clearance 0)
			)
			(min_thickness 0.25)
			(keepout
				(tracks not_allowed)
				(vias allowed)
				(pads allowed)
				(copperpour not_allowed)
				(footprints allowed)
			)
			(placement
				(enabled no)
				(sheetname "")
			)
			(fill
				(thermal_gap 0.5)
				(thermal_bridge_width 0.5)
				(island_removal_mode 0)
			)
			(polygon
				(pts
					(xy 79.756 -64.008) (xy 79.756 -64.516) (xy 80.137 -64.516) (xy 80.137 -64.008)
				)
			)
		)
		(zone
			(layer "B.Cu")
			(hatch none 0.5)
			(connect_pads
				(clearance 0)
			)
			(min_thickness 0.25)
			(keepout
				(tracks allowed)
				(vias not_allowed)
				(pads allowed)
				(copperpour not_allowed)
				(footprints allowed)
			)
			(placement
				(enabled no)
				(sheetname "")
			)
			(fill
				(thermal_gap 0.5)
				(thermal_bridge_width 0.5)
				(island_removal_mode 0)
			)
			(polygon
				(pts
					(xy 80.137 -64.008) (xy 80.137 -64.516) (xy 79.756 -64.516) (xy 79.756 -64.008)
				)
			)
		)
	)
	(footprint ""
		(layer "B.Cu")
		(at 469.138 -131.2164 180)
		(property "Reference" "CR6W2"
			(at -1.06934 -0.39116 270)
			(unlocked yes)
			(layer "B.SilkS")
			(effects
				(font
					(size 0.4064 0.254)
					(thickness 0.1524)
				)
				(justify left mirror)
			)
		)
		(property "Value" ""
			(at 0 0 0)
			(layer "B.Fab")
			(effects
				(font
					(size 1.27 1.27)
				)
				(justify mirror)
			)
		)
		(duplicate_pad_numbers_are_jumpers no)
		(fp_line
			(start 1.234186 1.636522)
			(end 0.753364 0.803656)
			(stroke
				(width 0.1524)
				(type default)
			)
			(layer "B.SilkS")
		)
		(fp_line
			(start 0.753364 2.548128)
			(end 0.753364 1.636522)
			(stroke
				(width 0.1524)
				(type default)
			)
			(layer "B.SilkS")
		)
		(fp_line
			(start 0.753364 1.636522)
			(end 1.234186 1.636522)
			(stroke
				(width 0.1524)
				(type default)
			)
			(layer "B.SilkS")
		)
		(fp_line
			(start 0.753364 0.803656)
			(end 0.272542 1.636522)
			(stroke
				(width 0.1524)
				(type default)
			)
			(layer "B.SilkS")
		)
		(fp_line
			(start 0.753364 -0.319786)
			(end 0.753364 0.803656)
			(stroke
				(width 0.1524)
				(type default)
			)
			(layer "B.SilkS")
		)
		(fp_line
			(start 0.272542 1.636522)
			(end 0.753364 1.636522)
			(stroke
				(width 0.1524)
				(type default)
			)
			(layer "B.SilkS")
		)
		(fp_line
			(start 0.272542 0.803656)
			(end 1.234186 0.803656)
			(stroke
				(width 0.1524)
				(type default)
			)
			(layer "B.SilkS")
		)
		(fp_poly
			(pts
				(xy 0.67437 0.24384) (xy 0.67437 2.04216) (xy -0.67437 2.04216) (xy -0.67437 0.24384)
			)
			(stroke
				(width 0)
				(type default)
			)
			(fill no)
			(layer "B.CrtYd")
		)
		(fp_line
			(start 1.229106 1.63195)
			(end 0.748284 0.799084)
			(stroke
				(width 0.1)
				(type default)
			)
			(layer "B.Fab")
		)
		(fp_line
			(start 0.752348 1.628902)
			(end 0.752348 2.540508)
			(stroke
				(width 0.1)
				(type default)
			)
			(layer "B.Fab")
		)
		(fp_line
			(start 0.748284 0.799084)
			(end 0.748284 -0.324358)
			(stroke
				(width 0.1)
				(type default)
			)
			(layer "B.Fab")
		)
		(fp_line
			(start 0.748284 0.799084)
			(end 0.267462 1.63195)
			(stroke
				(width 0.1)
				(type default)
			)
			(layer "B.Fab")
		)
		(fp_line
			(start 0.67437 2.04216)
			(end -0.67437 2.04216)
			(stroke
				(width 0.1)
				(type default)
			)
			(layer "B.Fab")
		)
		(fp_line
			(start 0.67437 0.24384)
			(end 0.67437 2.04216)
			(stroke
				(width 0.1)
				(type default)
			)
			(layer "B.Fab")
		)
		(fp_line
			(start 0.267462 1.63195)
			(end 1.229106 1.63195)
			(stroke
				(width 0.1)
				(type default)
			)
			(layer "B.Fab")
		)
		(fp_line
			(start 0.267462 0.799084)
			(end 1.229106 0.799084)
			(stroke
				(width 0.1)
				(type default)
			)
			(layer "B.Fab")
		)
		(fp_line
			(start -0.67437 2.04216)
			(end -0.67437 0.24384)
			(stroke
				(width 0.1)
				(type default)
			)
			(layer "B.Fab")
		)
		(fp_line
			(start -0.67437 0.24384)
			(end 0.67437 0.24384)
			(stroke
				(width 0.1)
				(type default)
			)
			(layer "B.Fab")
		)
		(pad "1" smd rect
			(at 0 0)
			(size 0.4064 1.016)
			(layers "B.Cu" "B.Mask" "B.Paste")
			(net "FM_CPU_MSMI_LVT3_N")
		)
		(pad "2" smd rect
			(at 0 2.286)
			(size 0.4064 1.016)
			(layers "B.Cu" "B.Mask" "B.Paste")
			(net "FM_CPU_CATERR_MSMI_LVT3_N")
		)
	)
	(footprint ""
		(layer "B.Cu")
		(at 327.025 -60.325 90)
		(property "Reference" "R4R1"
			(at 0 0 90)
			(layer "B.SilkS")
			(hide yes)
			(effects
				(font
					(size 1.27 1.27)
				)
				(justify mirror)
			)
		)
		(property "Value" ""
			(at 0 0 90)
			(layer "B.Fab")
			(effects
				(font
					(size 1.27 1.27)
				)
				(justify mirror)
			)
		)
		(duplicate_pad_numbers_are_jumpers no)
		(fp_poly
			(pts
				(xy 0.2794 -0.1016) (xy -0.2794 -0.1016) (xy -0.2794 0.9906) (xy 0.2794 0.9906)
			)
			(stroke
				(width 0)
				(type default)
			)
			(fill no)
			(layer "B.CrtYd")
		)
		(fp_line
			(start 0.2794 -0.1016)
			(end 0.2794 0.9906)
			(stroke
				(width 0.1)
				(type default)
			)
			(layer "B.Fab")
		)
		(fp_line
			(start -0.2794 -0.1016)
			(end 0.2794 -0.1016)
			(stroke
				(width 0.1)
				(type default)
			)
			(layer "B.Fab")
		)
		(fp_line
			(start 0.2794 0.9906)
			(end -0.2794 0.9906)
			(stroke
				(width 0.1)
				(type default)
			)
			(layer "B.Fab")
		)
		(fp_line
			(start -0.2794 0.9906)
			(end -0.2794 -0.1016)
			(stroke
				(width 0.1)
				(type default)
			)
			(layer "B.Fab")
		)
		(pad "1" smd rect
			(at 0 0 270)
			(size 0.508 0.508)
			(layers "B.Cu" "B.Mask" "B.Paste")
			(net "H_CPU0_FAST_WAKE_N")
		)
		(pad "2" smd rect
			(at 0 0.889 270)
			(size 0.508 0.508)
			(layers "B.Cu" "B.Mask" "B.Paste")
			(net "H_CPU0_FAST_WAKE_B_N")
		)
		(zone
			(layer "B.Cu")
			(hatch none 0.5)
			(connect_pads
				(clearance 0)
			)
			(min_thickness 0.25)
			(keepout
				(tracks allowed)
				(vias not_allowed)
				(pads allowed)
				(copperpour not_allowed)
				(footprints allowed)
			)
			(placement
				(enabled no)
				(sheetname "")
			)
			(fill
				(thermal_gap 0.5)
				(thermal_bridge_width 0.5)
				(island_removal_mode 0)
			)
			(polygon
				(pts
					(xy 327.279 -60.579) (xy 327.279 -60.071) (xy 327.66 -60.071) (xy 327.66 -60.579)
				)
			)
		)
		(zone
			(layer "B.Cu")
			(hatch none 0.5)
			(connect_pads
				(clearance 0)
			)
			(min_thickness 0.25)
			(keepout
				(tracks not_allowed)
				(vias allowed)
				(pads allowed)
				(copperpour not_allowed)
				(footprints allowed)
			)
			(placement
				(enabled no)
				(sheetname "")
			)
			(fill
				(thermal_gap 0.5)
				(thermal_bridge_width 0.5)
				(island_removal_mode 0)
			)
			(polygon
				(pts
					(xy 327.66 -60.579) (xy 327.66 -60.071) (xy 327.279 -60.071) (xy 327.279 -60.579)
				)
			)
		)
	)
	(footprint ""
		(layer "B.Cu")
		(at 411.479492 -31.107888 -90)
		(property "Reference" "C25W61"
			(at 0.8382 -0.67818 270)
			(unlocked yes)
			(layer "B.SilkS")
			(effects
				(font
					(size 0.4064 0.254)
					(thickness 0.1524)
				)
				(justify left mirror)
			)
		)
		(property "Value" ""
			(at 0 0 90)
			(layer "B.Fab")
			(effects
				(font
					(size 1.27 1.27)
				)
				(justify mirror)
			)
		)
		(duplicate_pad_numbers_are_jumpers no)
		(fp_poly
			(pts
				(xy -0.3048 -0.1016) (xy -0.3048 0.9906) (xy 0.3048 0.9906) (xy 0.3048 -0.1016)
			)
			(stroke
				(width 0)
				(type default)
			)
			(fill no)
			(layer "B.CrtYd")
		)
		(fp_line
			(start -0.3048 0.9906)
			(end -0.3048 -0.1016)
			(stroke
				(width 0.1)
				(type default)
			)
			(layer "B.Fab")
		)
		(fp_line
			(start 0.3048 0.9906)
			(end -0.3048 0.9906)
			(stroke
				(width 0.1)
				(type default)
			)
			(layer "B.Fab")
		)
		(fp_line
			(start -0.3048 -0.1016)
			(end 0.3048 -0.1016)
			(stroke
				(width 0.1)
				(type default)
			)
			(layer "B.Fab")
		)
		(fp_line
			(start 0.3048 -0.1016)
			(end 0.3048 0.9906)
			(stroke
				(width 0.1)
				(type default)
			)
			(layer "B.Fab")
		)
		(pad "1" smd rect
			(at 0 0 90)
			(size 0.508 0.508)
			(layers "B.Cu" "B.Mask" "B.Paste")
			(net "P3V3_STBY")
		)
		(pad "2" smd rect
			(at 0 0.889 90)
			(size 0.508 0.508)
			(layers "B.Cu" "B.Mask" "B.Paste")
			(net "GND")
		)
		(zone
			(layer "B.Cu")
			(hatch none 0.5)
			(connect_pads
				(clearance 0)
			)
			(min_thickness 0.25)
			(keepout
				(tracks not_allowed)
				(vias allowed)
				(pads allowed)
				(copperpour not_allowed)
				(footprints allowed)
			)
			(placement
				(enabled no)
				(sheetname "")
			)
			(fill
				(thermal_gap 0.5)
				(thermal_bridge_width 0.5)
				(island_removal_mode 0)
			)
			(polygon
				(pts
					(xy 410.844492 -30.853888) (xy 410.844492 -31.361888) (xy 411.225492 -31.361888) (xy 411.225492 -30.853888)
				)
			)
		)
		(zone
			(layer "B.Cu")
			(hatch none 0.5)
			(connect_pads
				(clearance 0)
			)
			(min_thickness 0.25)
			(keepout
				(tracks allowed)
				(vias not_allowed)
				(pads allowed)
				(copperpour not_allowed)
				(footprints allowed)
			)
			(placement
				(enabled no)
				(sheetname "")
			)
			(fill
				(thermal_gap 0.5)
				(thermal_bridge_width 0.5)
				(island_removal_mode 0)
			)
			(polygon
				(pts
					(xy 411.225492 -30.853888) (xy 411.225492 -31.361888) (xy 410.844492 -31.361888) (xy 410.844492 -30.853888)
				)
			)
		)
	)
	(footprint ""
		(layer "B.Cu")
		(at 205.74 -106.299 -90)
		(property "Reference" "R6N10"
			(at 0 0 90)
			(layer "B.SilkS")
			(hide yes)
			(effects
				(font
					(size 1.27 1.27)
				)
				(justify mirror)
			)
		)
		(property "Value" ""
			(at 0 0 90)
			(layer "B.Fab")
			(effects
				(font
					(size 1.27 1.27)
				)
				(justify mirror)
			)
		)
		(duplicate_pad_numbers_are_jumpers no)
		(fp_poly
			(pts
				(xy 0.2794 -0.1016) (xy -0.2794 -0.1016) (xy -0.2794 0.9906) (xy 0.2794 0.9906)
			)
			(stroke
				(width 0)
				(type default)
			)
			(fill no)
			(layer "B.CrtYd")
		)
		(fp_line
			(start -0.2794 0.9906)
			(end -0.2794 -0.1016)
			(stroke
				(width 0.1)
				(type default)
			)
			(layer "B.Fab")
		)
		(fp_line
			(start 0.2794 0.9906)
			(end -0.2794 0.9906)
			(stroke
				(width 0.1)
				(type default)
			)
			(layer "B.Fab")
		)
		(fp_line
			(start -0.2794 -0.1016)
			(end 0.2794 -0.1016)
			(stroke
				(width 0.1)
				(type default)
			)
			(layer "B.Fab")
		)
		(fp_line
			(start 0.2794 -0.1016)
			(end 0.2794 0.9906)
			(stroke
				(width 0.1)
				(type default)
			)
			(layer "B.Fab")
		)
		(pad "1" smd rect
			(at 0 0 90)
			(size 0.508 0.508)
			(layers "B.Cu" "B.Mask" "B.Paste")
			(net "SVID_ALERT0_CPU0_N")
		)
		(pad "2" smd rect
			(at 0 0.889 90)
			(size 0.508 0.508)
			(layers "B.Cu" "B.Mask" "B.Paste")
			(net "SVID_ALERT0_CPU0_R_N")
		)
		(zone
			(layer "B.Cu")
			(hatch none 0.5)
			(connect_pads
				(clearance 0)
			)
			(min_thickness 0.25)
			(keepout
				(tracks not_allowed)
				(vias allowed)
				(pads allowed)
				(copperpour not_allowed)
				(footprints allowed)
			)
			(placement
				(enabled no)
				(sheetname "")
			)
			(fill
				(thermal_gap 0.5)
				(thermal_bridge_width 0.5)
				(island_removal_mode 0)
			)
			(polygon
				(pts
					(xy 205.105 -106.045) (xy 205.105 -106.553) (xy 205.486 -106.553) (xy 205.486 -106.045)
				)
			)
		)
		(zone
			(layer "B.Cu")
			(hatch none 0.5)
			(connect_pads
				(clearance 0)
			)
			(min_thickness 0.25)
			(keepout
				(tracks allowed)
				(vias not_allowed)
				(pads allowed)
				(copperpour not_allowed)
				(footprints allowed)
			)
			(placement
				(enabled no)
				(sheetname "")
			)
			(fill
				(thermal_gap 0.5)
				(thermal_bridge_width 0.5)
				(island_removal_mode 0)
			)
			(polygon
				(pts
					(xy 205.486 -106.045) (xy 205.486 -106.553) (xy 205.105 -106.553) (xy 205.105 -106.045)
				)
			)
		)
	)
	(footprint ""
		(layer "B.Cu")
		(at 19.431 -82.423 -90)
		(property "Reference" "R9P11"
			(at 0 0 90)
			(layer "B.SilkS")
			(hide yes)
			(effects
				(font
					(size 1.27 1.27)
				)
				(justify mirror)
			)
		)
		(property "Value" ""
			(at 0 0 90)
			(layer "B.Fab")
			(effects
				(font
					(size 1.27 1.27)
				)
				(justify mirror)
			)
		)
		(duplicate_pad_numbers_are_jumpers no)
		(fp_poly
			(pts
				(xy 0.2794 -0.1016) (xy -0.2794 -0.1016) (xy -0.2794 0.9906) (xy 0.2794 0.9906)
			)
			(stroke
				(width 0)
				(type default)
			)
			(fill no)
			(layer "B.CrtYd")
		)
		(fp_line
			(start -0.2794 0.9906)
			(end -0.2794 -0.1016)
			(stroke
				(width 0.1)
				(type default)
			)
			(layer "B.Fab")
		)
		(fp_line
			(start 0.2794 0.9906)
			(end -0.2794 0.9906)
			(stroke
				(width 0.1)
				(type default)
			)
			(layer "B.Fab")
		)
		(fp_line
			(start -0.2794 -0.1016)
			(end 0.2794 -0.1016)
			(stroke
				(width 0.1)
				(type default)
			)
			(layer "B.Fab")
		)
		(fp_line
			(start 0.2794 -0.1016)
			(end 0.2794 0.9906)
			(stroke
				(width 0.1)
				(type default)
			)
			(layer "B.Fab")
		)
		(pad "1" smd rect
			(at 0 0 90)
			(size 0.508 0.508)
			(layers "B.Cu" "B.Mask" "B.Paste")
			(net "A_P12V_STBY_FP_TRIGGER")
		)
		(pad "2" smd rect
			(at 0 0.889 90)
			(size 0.508 0.508)
			(layers "B.Cu" "B.Mask" "B.Paste")
			(net "AGND_HSC")
		)
		(zone
			(layer "B.Cu")
			(hatch none 0.5)
			(connect_pads
				(clearance 0)
			)
			(min_thickness 0.25)
			(keepout
				(tracks not_allowed)
				(vias allowed)
				(pads allowed)
				(copperpour not_allowed)
				(footprints allowed)
			)
			(placement
				(enabled no)
				(sheetname "")
			)
			(fill
				(thermal_gap 0.5)
				(thermal_bridge_width 0.5)
				(island_removal_mode 0)
			)
			(polygon
				(pts
					(xy 18.796 -82.169) (xy 18.796 -82.677) (xy 19.177 -82.677) (xy 19.177 -82.169)
				)
			)
		)
		(zone
			(layer "B.Cu")
			(hatch none 0.5)
			(connect_pads
				(clearance 0)
			)
			(min_thickness 0.25)
			(keepout
				(tracks allowed)
				(vias not_allowed)
				(pads allowed)
				(copperpour not_allowed)
				(footprints allowed)
			)
			(placement
				(enabled no)
				(sheetname "")
			)
			(fill
				(thermal_gap 0.5)
				(thermal_bridge_width 0.5)
				(island_removal_mode 0)
			)
			(polygon
				(pts
					(xy 19.177 -82.169) (xy 19.177 -82.677) (xy 18.796 -82.677) (xy 18.796 -82.169)
				)
			)
		)
	)
)
